(kicad_pcb
	(version 20241229)
	(generator "pcbnew")
	(generator_version "9.0")
	(general
		(thickness 1.6296)
		(legacy_teardrops no)
	)
	(paper "A3")
	(title_block
		(title "Thunderbolt to 10GbE adapter")
		(date "2026-04-21")
		(rev "1.1.0")
		(company "Antmicro Ltd")
		(comment 1 "www.antmicro.com")
		(comment 9 "footprints 318-321 of 703")
	)
	(layers
		(0 "F.Cu" signal)
		(4 "In1.Cu" signal)
		(6 "In2.Cu" signal)
		(8 "In3.Cu" signal)
		(10 "In4.Cu" signal)
		(12 "In5.Cu" signal)
		(14 "In6.Cu" signal)
		(2 "B.Cu" signal)
		(9 "F.Adhes" user "F.Adhesive")
		(11 "B.Adhes" user "B.Adhesive")
		(13 "F.Paste" user)
		(15 "B.Paste" user)
		(5 "F.SilkS" user "F.Silkscreen")
		(7 "B.SilkS" user "B.Silkscreen")
		(1 "F.Mask" user)
		(3 "B.Mask" user)
		(17 "Dwgs.User" user "User.Drawings")
		(19 "Cmts.User" user "User.Comments")
		(21 "Eco1.User" user "User.Eco1")
		(23 "Eco2.User" user "User.Eco2")
		(25 "Edge.Cuts" user)
		(27 "Margin" user)
		(31 "F.CrtYd" user "F.Courtyard")
		(29 "B.CrtYd" user "B.Courtyard")
		(35 "F.Fab" user)
		(33 "B.Fab" user)
	)
	(footprint "antmicro-footprints:R_0402_1005Metric"
		(layer "F.Cu")
		(at 131.52 116.5 90)
		(descr "Resistor SMD 0402")
		(tags "resistor SMD 0402")
		(property "Reference" "R69"
			(at 0.9 0.290003 90)
			(layer "F.SilkS")
			(effects
				(font
					(size 0.7 0.7)
					(thickness 0.15)
				)
				(justify left bottom)
			)
		)
		(property "Value" "R_100R_0402"
			(at -1.011843 1.772047 90)
			(layer "F.Fab")
			(effects
				(font
					(size 0.7 0.7)
					(thickness 0.15)
				)
				(justify left bottom)
			)
		)
		(property "Datasheet" "https://www.bourns.com/docs/product-datasheets/cr.pdf"
			(at 0 0 90)
			(layer "F.Fab")
			(hide yes)
			(effects
				(font
					(size 1.27 1.27)
					(thickness 0.15)
				)
			)
		)
		(property "Description" "SMD Chip Resistor, 100 ohm, ± 1%, 62.5 mW, 0402 [1005 Metric], Thick Film, General Purpose"
			(at 0 0 90)
			(layer "F.Fab")
			(hide yes)
			(effects
				(font
					(size 1.27 1.27)
					(thickness 0.15)
				)
			)
		)
		(property "MPN" "CR0402-FX-1000GLF"
			(at 0 0 90)
			(unlocked yes)
			(layer "F.Fab")
			(hide yes)
			(effects
				(font
					(size 1 1)
					(thickness 0.15)
				)
			)
		)
		(property "Manufacturer" "Bourns"
			(at 0 0 90)
			(unlocked yes)
			(layer "F.Fab")
			(hide yes)
			(effects
				(font
					(size 1 1)
					(thickness 0.15)
				)
			)
		)
		(property "License" "Apache-2.0"
			(at 0 0 90)
			(unlocked yes)
			(layer "F.Fab")
			(hide yes)
			(effects
				(font
					(size 1 1)
					(thickness 0.15)
				)
			)
		)
		(property "Val" "100R"
			(at 0 0 90)
			(unlocked yes)
			(layer "F.Fab")
			(hide yes)
			(effects
				(font
					(size 1 1)
					(thickness 0.15)
				)
			)
		)
		(property "Tolerance" "1%"
			(at 0 0 90)
			(unlocked yes)
			(layer "F.Fab")
			(hide yes)
			(effects
				(font
					(size 1 1)
					(thickness 0.15)
				)
			)
		)
		(property "Author" "Antmicro"
			(at 0 0 90)
			(unlocked yes)
			(layer "F.Fab")
			(hide yes)
			(effects
				(font
					(size 1 1)
					(thickness 0.15)
				)
			)
		)
		(sheetname "/TB Controller/")
		(sheetfile "tb.kicad_sch")
		(attr smd)
		(fp_rect
			(start -0.925 -0.47)
			(end 0.925 0.47)
			(stroke
				(width 0.05)
				(type default)
			)
			(fill no)
			(layer "F.CrtYd")
		)
		(fp_rect
			(start -0.5 -0.25)
			(end 0.5 0.25)
			(stroke
				(width 0.15)
				(type solid)
			)
			(fill no)
			(layer "F.Fab")
		)
		(fp_text user "${REFERENCE}"
			(at -0.95 3.168 90)
			(layer "F.Fab")
			(effects
				(font
					(size 0.7 0.7)
					(thickness 0.15)
				)
				(justify left bottom)
			)
		)
		(fp_text user "License: Apache-2.0"
			(at -0.95 5.169 90)
			(layer "F.Fab")
			(effects
				(font
					(size 0.7 0.7)
					(thickness 0.15)
				)
				(justify left bottom)
			)
		)
		(fp_text user "Author: Antmicro"
			(at -0.95 4.169 90)
			(layer "F.Fab")
			(effects
				(font
					(size 0.7 0.7)
					(thickness 0.15)
				)
				(justify left bottom)
			)
		)
		(pad "1" smd roundrect
			(at -0.48 0 90)
			(size 0.59 0.64)
			(layers "F.Cu" "F.Mask" "F.Paste")
			(roundrect_rratio 0.25)
			(net 238 "Net-(U4D-TEST_PWR_GOOD)")
			(pintype "passive")
		)
		(pad "2" smd roundrect
			(at 0.48 0 90)
			(size 0.59 0.64)
			(layers "F.Cu" "F.Mask" "F.Paste")
			(roundrect_rratio 0.25)
			(net 23 "GND")
			(pintype "passive")
		)
	)
	(footprint "antmicro-footprints:LED_0603_1608Metric_G"
		(layer "F.Cu")
		(at 183.2 71.5)
		(descr "LED SMD 0603 Green")
		(tags "LED SMD 0603 Green")
		(property "Reference" "D7"
			(at -1.2 7.25 0)
			(layer "F.SilkS")
			(effects
				(font
					(size 0.7 0.7)
					(thickness 0.15)
				)
				(justify left bottom)
			)
		)
		(property "Value" "LED_G_0603_LG_L29K-G2J1-24-Z"
			(at -0.001 1.599 0)
			(layer "F.Fab")
			(effects
				(font
					(size 0.7 0.7)
					(thickness 0.15)
				)
				(justify left bottom)
			)
		)
		(property "Datasheet" "https://look.ams-osram.com/m/19ee86b3ae0ee95b/original/LG-L29K.pdf"
			(at 0 0 0)
			(layer "F.Fab")
			(hide yes)
			(effects
				(font
					(size 1.27 1.27)
					(thickness 0.15)
				)
			)
		)
		(property "Description" "LED, Green, SMD, 0603, 20 mA, 1.7 V, 570 nm"
			(at 0 0 0)
			(layer "F.Fab")
			(hide yes)
			(effects
				(font
					(size 1.27 1.27)
					(thickness 0.15)
				)
			)
		)
		(property "MPN" "LG L29K-G2J1-24-Z"
			(at 0 0 0)
			(unlocked yes)
			(layer "F.Fab")
			(hide yes)
			(effects
				(font
					(size 1 1)
					(thickness 0.15)
				)
			)
		)
		(property "Manufacturer" "OSRAM"
			(at 0 0 0)
			(unlocked yes)
			(layer "F.Fab")
			(hide yes)
			(effects
				(font
					(size 1 1)
					(thickness 0.15)
				)
			)
		)
		(property "Color" "Green"
			(at 0 0 0)
			(unlocked yes)
			(layer "F.Fab")
			(hide yes)
			(effects
				(font
					(size 1 1)
					(thickness 0.15)
				)
			)
		)
		(property "Author" "Antmicro"
			(at 0 0 0)
			(unlocked yes)
			(layer "F.Fab")
			(hide yes)
			(effects
				(font
					(size 1 1)
					(thickness 0.15)
				)
			)
		)
		(property "License" "Apache-2.0"
			(at 0 0 0)
			(unlocked yes)
			(layer "F.Fab")
			(hide yes)
			(effects
				(font
					(size 1 1)
					(thickness 0.15)
				)
			)
		)
		(sheetname "/X710 DCDC converters/")
		(sheetfile "DCDC_converters_X710.kicad_sch")
		(attr smd)
		(fp_line
			(start -1.18 -0.319)
			(end -1.18 0.321)
			(stroke
				(width 0.15)
				(type solid)
			)
			(layer "F.SilkS")
		)
		(fp_line
			(start -0.094672 0.001008)
			(end -0.24 0.001008)
			(stroke
				(width 0.1)
				(type solid)
			)
			(layer "F.SilkS")
		)
		(fp_line
			(start -0.094672 0.001008)
			(end 0.105328 -0.198992)
			(stroke
				(width 0.1)
				(type solid)
			)
			(layer "F.SilkS")
		)
		(fp_line
			(start -0.094672 0.201008)
			(end -0.094672 -0.198992)
			(stroke
				(width 0.1)
				(type solid)
			)
			(layer "F.SilkS")
		)
		(fp_line
			(start 0.105328 0.001008)
			(end 0.24 0.001)
			(stroke
				(width 0.1)
				(type solid)
			)
			(layer "F.SilkS")
		)
		(fp_line
			(start 0.105328 0.201008)
			(end -0.094672 0.001008)
			(stroke
				(width 0.1)
				(type solid)
			)
			(layer "F.SilkS")
		)
		(fp_line
			(start 0.105328 0.201008)
			(end 0.105328 -0.198992)
			(stroke
				(width 0.1)
				(type solid)
			)
			(layer "F.SilkS")
		)
		(fp_line
			(start 0.22 -0.35)
			(end -0.22 -0.35)
			(stroke
				(width 0.15)
				(type solid)
			)
			(layer "F.SilkS")
		)
		(fp_line
			(start 0.22 0.35)
			(end -0.22 0.35)
			(stroke
				(width 0.15)
				(type solid)
			)
			(layer "F.SilkS")
		)
		(fp_rect
			(start 1.25 0.65)
			(end -1.25 -0.65)
			(stroke
				(width 0.05)
				(type solid)
			)
			(fill no)
			(layer "F.CrtYd")
		)
		(fp_line
			(start -0.199 -0.202)
			(end -0.199 0.1)
			(stroke
				(width 0.15)
				(type solid)
			)
			(layer "F.Fab")
		)
		(fp_line
			(start -0.199 0)
			(end -0.597 0)
			(stroke
				(width 0.15)
				(type solid)
			)
			(layer "F.Fab")
		)
		(fp_line
			(start -0.199 0.2)
			(end -0.199 0.1)
			(stroke
				(width 0.15)
				(type solid)
			)
			(layer "F.Fab")
		)
		(fp_line
			(start -0.101 0)
			(end 0.201 0.2)
			(stroke
				(width 0.15)
				(type solid)
			)
			(layer "F.Fab")
		)
		(fp_line
			(start 0.201 -0.202)
			(end -0.101 0)
			(stroke
				(width 0.15)
				(type solid)
			)
			(layer "F.Fab")
		)
		(fp_line
			(start 0.201 0)
			(end 0.201 -0.202)
			(stroke
				(width 0.15)
				(type solid)
			)
			(layer "F.Fab")
		)
		(fp_line
			(start 0.201 0.2)
			(end 0.201 0)
			(stroke
				(width 0.15)
				(type solid)
			)
			(layer "F.Fab")
		)
		(fp_line
			(start 0.599 0)
			(end 0.201 0)
			(stroke
				(width 0.15)
				(type solid)
			)
			(layer "F.Fab")
		)
		(fp_rect
			(start 0.848 0.4)
			(end -0.85 -0.402)
			(stroke
				(width 0.15)
				(type solid)
			)
			(fill no)
			(layer "F.Fab")
		)
		(fp_text user "${REFERENCE}"
			(at -1.4224 5.999 0)
			(layer "F.Fab")
			(effects
				(font
					(size 0.7 0.7)
					(thickness 0.15)
				)
				(justify left bottom)
			)
		)
		(fp_text user "License: Apache-2.0"
			(at -1.4224 3.599 0)
			(layer "F.Fab")
			(effects
				(font
					(size 0.7 0.7)
					(thickness 0.15)
				)
				(justify left bottom)
			)
		)
		(fp_text user "Author: Antmicro"
			(at -1.4224 4.799 0)
			(layer "F.Fab")
			(effects
				(font
					(size 0.7 0.7)
					(thickness 0.15)
				)
				(justify left bottom)
			)
		)
		(pad "1" smd roundrect
			(at -0.7 0 180)
			(size 0.8 1)
			(layers "F.Cu" "F.Mask" "F.Paste")
			(roundrect_rratio 0.2)
			(net 415 "Net-(D7-C)")
			(pinfunction "C")
			(pintype "passive")
		)
		(pad "2" smd roundrect
			(at 0.7 0 180)
			(size 0.8 1)
			(layers "F.Cu" "F.Mask" "F.Paste")
			(roundrect_rratio 0.2)
			(net 334 "/X710 DCDC converters/+3V3_OUT")
			(pinfunction "A")
			(pintype "passive")
		)
	)
	(footprint "antmicro-footprints:R_0402_1005Metric"
		(layer "F.Cu")
		(at 162 46.3 -90)
		(descr "Resistor SMD 0402")
		(tags "resistor SMD 0402")
		(property "Reference" "R232"
			(at 1.9 -6.3 270)
			(layer "F.SilkS")
			(effects
				(font
					(size 0.7 0.7)
					(thickness 0.15)
				)
				(justify left bottom)
			)
		)
		(property "Value" "R_10k_0402"
			(at -1.011843 1.772047 270)
			(layer "F.Fab")
			(effects
				(font
					(size 0.7 0.7)
					(thickness 0.15)
				)
				(justify left bottom)
			)
		)
		(property "Datasheet" "https://www.bourns.com/docs/product-datasheets/cr.pdf"
			(at 0 0 270)
			(layer "F.Fab")
			(hide yes)
			(effects
				(font
					(size 1.27 1.27)
					(thickness 0.15)
				)
			)
		)
		(property "Description" "SMD Chip Resistor, 10 kohm, ± 1%, 62.5 mW, 0402 [1005 Metric], Thick Film, General Purpose"
			(at 0 0 270)
			(layer "F.Fab")
			(hide yes)
			(effects
				(font
					(size 1.27 1.27)
					(thickness 0.15)
				)
			)
		)
		(property "MPN" "CR0402-FX-1002GLF"
			(at 0 0 270)
			(unlocked yes)
			(layer "F.Fab")
			(hide yes)
			(effects
				(font
					(size 1 1)
					(thickness 0.15)
				)
			)
		)
		(property "Manufacturer" "Bourns"
			(at 0 0 270)
			(unlocked yes)
			(layer "F.Fab")
			(hide yes)
			(effects
				(font
					(size 1 1)
					(thickness 0.15)
				)
			)
		)
		(property "License" "Apache-2.0"
			(at 0 0 270)
			(unlocked yes)
			(layer "F.Fab")
			(hide yes)
			(effects
				(font
					(size 1 1)
					(thickness 0.15)
				)
			)
		)
		(property "Author" "Antmicro"
			(at 0 0 270)
			(unlocked yes)
			(layer "F.Fab")
			(hide yes)
			(effects
				(font
					(size 1 1)
					(thickness 0.15)
				)
			)
		)
		(property "Val" "10k"
			(at 0 0 270)
			(unlocked yes)
			(layer "F.Fab")
			(hide yes)
			(effects
				(font
					(size 1 1)
					(thickness 0.15)
				)
			)
		)
		(property "Tolerance" "1%"
			(at 0 0 270)
			(unlocked yes)
			(layer "F.Fab")
			(hide yes)
			(effects
				(font
					(size 1 1)
					(thickness 0.15)
				)
			)
		)
		(sheetname "/Power input/")
		(sheetfile "power_input.kicad_sch")
		(attr smd)
		(fp_rect
			(start -0.925 -0.47)
			(end 0.925 0.47)
			(stroke
				(width 0.05)
				(type default)
			)
			(fill no)
			(layer "F.CrtYd")
		)
		(fp_rect
			(start -0.5 -0.25)
			(end 0.5 0.25)
			(stroke
				(width 0.15)
				(type solid)
			)
			(fill no)
			(layer "F.Fab")
		)
		(fp_text user "${REFERENCE}"
			(at -0.95 3.168 270)
			(layer "F.Fab")
			(effects
				(font
					(size 0.7 0.7)
					(thickness 0.15)
				)
				(justify left bottom)
			)
		)
		(fp_text user "Author: Antmicro"
			(at -0.95 4.169 270)
			(layer "F.Fab")
			(effects
				(font
					(size 0.7 0.7)
					(thickness 0.15)
				)
				(justify left bottom)
			)
		)
		(fp_text user "License: Apache-2.0"
			(at -0.95 5.169 270)
			(layer "F.Fab")
			(effects
				(font
					(size 0.7 0.7)
					(thickness 0.15)
				)
				(justify left bottom)
			)
		)
		(pad "1" smd roundrect
			(at -0.48 0 270)
			(size 0.59 0.64)
			(layers "F.Cu" "F.Mask" "F.Paste")
			(roundrect_rratio 0.25)
			(net 23 "GND")
			(pintype "passive")
		)
		(pad "2" smd roundrect
			(at 0.48 0 270)
			(size 0.59 0.64)
			(layers "F.Cu" "F.Mask" "F.Paste")
			(roundrect_rratio 0.25)
			(net 391 "/Power input/5V_FB")
			(pintype "passive")
		)
	)
	(footprint "antmicro-footprints:C_0402_1005Metric"
		(layer "F.Cu")
		(at 116.4 103.1)
		(descr "Capacitor SMD 0402")
		(tags "capacitor SMD 0402")
		(property "Reference" "C11"
			(at 0 -8.1 0)
			(layer "F.SilkS")
			(effects
				(font
					(size 0.7 0.7)
					(thickness 0.15)
				)
			)
		)
		(property "Value" "C_1u_0402"
			(at -1.022927 2.155213 0)
			(layer "F.Fab")
			(effects
				(font
					(size 0.7 0.7)
					(thickness 0.15)
				)
				(justify left bottom)
			)
		)
		(property "Datasheet" "https://product.tdk.com/en/search/capacitor/ceramic/mlcc/info?part_no=C1005X6S1A105K050BC"
			(at 0 0 0)
			(layer "F.Fab")
			(hide yes)
			(effects
				(font
					(size 1.27 1.27)
					(thickness 0.15)
				)
			)
		)
		(property "Description" "SMD Multilayer Ceramic Capacitor, 1 µF, 10 V, 0402 [1005 Metric], ± 10%, X6S, C"
			(at 0 0 0)
			(layer "F.Fab")
			(hide yes)
			(effects
				(font
					(size 1.27 1.27)
					(thickness 0.15)
				)
			)
		)
		(property "MPN" "C1005X6S1A105K050BC"
			(at 0 0 0)
			(unlocked yes)
			(layer "F.Fab")
			(hide yes)
			(effects
				(font
					(size 1 1)
					(thickness 0.15)
				)
			)
		)
		(property "Manufacturer" "TDK"
			(at 0 0 0)
			(unlocked yes)
			(layer "F.Fab")
			(hide yes)
			(effects
				(font
					(size 1 1)
					(thickness 0.15)
				)
			)
		)
		(property "License" "Apache-2.0"
			(at 0 0 0)
			(unlocked yes)
			(layer "F.Fab")
			(hide yes)
			(effects
				(font
					(size 1 1)
					(thickness 0.15)
				)
			)
		)
		(property "Val" "1u"
			(at 0 0 0)
			(unlocked yes)
			(layer "F.Fab")
			(hide yes)
			(effects
				(font
					(size 1 1)
					(thickness 0.15)
				)
			)
		)
		(property "Voltage" ""
			(at 0 0 0)
			(unlocked yes)
			(layer "F.Fab")
			(hide yes)
			(effects
				(font
					(size 1 1)
					(thickness 0.15)
				)
			)
		)
		(property "Dielectric" ""
			(at 0 0 0)
			(unlocked yes)
			(layer "F.Fab")
			(hide yes)
			(effects
				(font
					(size 1 1)
					(thickness 0.15)
				)
			)
		)
		(property "Author" "Antmicro"
			(at 0 0 0)
			(unlocked yes)
			(layer "F.Fab")
			(hide yes)
			(effects
				(font
					(size 1 1)
					(thickness 0.15)
				)
			)
		)
		(sheetname "/PD and TB DC-DC/")
		(sheetfile "PD_and_TB_DC_DC.kicad_sch")
		(attr smd)
		(fp_rect
			(start -0.925 -0.47)
			(end 0.925 0.47)
			(stroke
				(width 0.05)
				(type default)
			)
			(fill no)
			(layer "F.CrtYd")
		)
		(fp_line
			(start -0.494 -0.25)
			(end 0.504 -0.25)
			(stroke
				(width 0.15)
				(type solid)
			)
			(layer "F.Fab")
		)
		(fp_line
			(start -0.494 0.248)
			(end -0.494 -0.25)
			(stroke
				(width 0.15)
				(type solid)
			)
			(layer "F.Fab")
		)
		(fp_line
			(start 0.504 -0.25)
			(end 0.504 0.248)
			(stroke
				(width 0.15)
				(type solid)
			)
			(layer "F.Fab")
		)
		(fp_line
			(start 0.504 0.248)
			(end -0.494 0.248)
			(stroke
				(width 0.15)
				(type solid)
			)
			(layer "F.Fab")
		)
		(fp_text user "License: Apache-2.0"
			(at -0.939 5.799 0)
			(layer "F.Fab")
			(effects
				(font
					(size 0.7 0.7)
					(thickness 0.15)
				)
				(justify left bottom)
			)
		)
		(fp_text user "${REFERENCE}"
			(at -0.939 4.599 0)
			(layer "F.Fab")
			(effects
				(font
					(size 0.7 0.7)
					(thickness 0.15)
				)
				(justify left bottom)
			)
		)
		(fp_text user "Author: Antmicro"
			(at -0.939 3.399 0)
			(layer "F.Fab")
			(effects
				(font
					(size 0.7 0.7)
					(thickness 0.15)
				)
				(justify left bottom)
			)
		)
		(pad "1" smd roundrect
			(at -0.48 0)
			(size 0.59 0.64)
			(layers "F.Cu" "F.Mask" "F.Paste")
			(roundrect_rratio 0.25)
			(net 23 "GND")
			(pintype "passive")
		)
		(pad "2" smd roundrect
			(at 0.48 0)
			(size 0.59 0.64)
			(layers "F.Cu" "F.Mask" "F.Paste")
			(roundrect_rratio 0.25)
			(net 303 "/PD and TB DC-DC/SMPS_LDO")
			(pintype "passive")
		)
	)
)
